# BASEBOARD_FAB2 (Tioga Pass) — schematic netlist excerpt (pin names and nets, part order shuffled) for the footprints in the layout excerpt that follows; sources: Cadence DE-HDL packaged netlist, KiCad conversion of Wiwynn_Tioga_Pass_MB.brd

R12W31  RES  0.0 5% CHIP  pkg 0402  page 223 : A = PU_VR_PVDDQ_GHJ_FAULT1 ; B = PWRGD_PVDDQ_GHJ
R4D69  RES  4.75K 1% CHIP  pkg 0402  page 102 : A = P3V3 ; B = FM_CPU1_MCP_CLK_EN_N

(kicad_pcb
	(version 20260206)
	(generator "pcbnew")
	(generator_version "10.0")
	(general
		(thickness 1.6)
		(legacy_teardrops no)
	)
	(paper "A4")
	(title_block
		(title "Wiwynn_Tioga_Pass_MB.brd")
		(comment 1 "Tioga Pass / footprints 435-436 of 4770")
	)
	(layers
		(0 "F.Cu" signal "TOP")
		(4 "In1.Cu" signal "L2GND")
		(6 "In2.Cu" signal "L3")
		(8 "In3.Cu" signal "L4GND")
		(10 "In4.Cu" signal "L5")
		(12 "In5.Cu" signal "L6GND")
		(14 "In6.Cu" signal "L7VCC")
		(16 "In7.Cu" signal "L8VCC")
		(18 "In8.Cu" signal "L9GND")
		(20 "In9.Cu" signal "L10")
		(22 "In10.Cu" signal "L11GND")
		(24 "In11.Cu" signal "L12")
		(26 "In12.Cu" signal "L13GND")
		(2 "B.Cu" signal "BOTTOM")
		(9 "F.Adhes" user "F.Adhesive")
		(11 "B.Adhes" user "B.Adhesive")
		(13 "F.Paste" user "Package Geometry/Pastemask Top")
		(15 "B.Paste" user "Package Geometry/Pastemask Bottom")
		(5 "F.SilkS" user "Ref Des/Silkscreen Top")
		(7 "B.SilkS" user "Ref Des/Silkscreen Bottom")
		(1 "F.Mask" user "Board Geometry/Soldermask Top")
		(3 "B.Mask" user "Board Geometry/Soldermask Bottom")
		(17 "Dwgs.User" user "User.Drawings")
		(19 "Cmts.User" user "User.Comments")
		(21 "Eco1.User" user "User.Eco1")
		(23 "Eco2.User" user "User.Eco2")
		(25 "Edge.Cuts" user "Board Geometry/Outline")
		(27 "Margin" user)
		(31 "F.CrtYd" user "Package Geometry/Place Bound Top")
		(29 "B.CrtYd" user "Package Geometry/Place Bound Bottom")
		(35 "F.Fab" user "Ref Des/Assembly Top")
		(33 "B.Fab" user "Ref Des/Assembly Bottom")
	)
	(footprint ""
		(layer "F.Cu")
		(at 178.054 -84.328 180)
		(property "Reference" "R4D69"
			(at 0 0 180)
			(layer "F.SilkS")
			(hide yes)
			(effects
				(font
					(size 1.27 1.27)
				)
			)
		)
		(property "Value" ""
			(at 0 0 180)
			(layer "F.Fab")
			(effects
				(font
					(size 1.27 1.27)
				)
			)
		)
		(duplicate_pad_numbers_are_jumpers no)
		(fp_poly
			(pts
				(xy -0.2794 -0.1016) (xy 0.2794 -0.1016) (xy 0.2794 0.9906) (xy -0.2794 0.9906)
			)
			(stroke
				(width 0)
				(type default)
			)
			(fill no)
			(layer "F.CrtYd")
		)
		(fp_line
			(start 0.2794 0.9906)
			(end 0.2794 -0.1016)
			(stroke
				(width 0.1)
				(type default)
			)
			(layer "F.Fab")
		)
		(fp_line
			(start 0.2794 -0.1016)
			(end -0.2794 -0.1016)
			(stroke
				(width 0.1)
				(type default)
			)
			(layer "F.Fab")
		)
		(fp_line
			(start -0.2794 0.9906)
			(end 0.2794 0.9906)
			(stroke
				(width 0.1)
				(type default)
			)
			(layer "F.Fab")
		)
		(fp_line
			(start -0.2794 -0.1016)
			(end -0.2794 0.9906)
			(stroke
				(width 0.1)
				(type default)
			)
			(layer "F.Fab")
		)
		(pad "1" smd rect
			(at 0 0 180)
			(size 0.508 0.508)
			(layers "F.Cu" "F.Mask" "F.Paste")
			(net "P3V3")
		)
		(pad "2" smd rect
			(at 0 0.889 180)
			(size 0.508 0.508)
			(layers "F.Cu" "F.Mask" "F.Paste")
			(net "FM_CPU1_MCP_CLK_EN_N")
		)
		(zone
			(layer "F.Cu")
			(hatch none 0.5)
			(connect_pads
				(clearance 0)
			)
			(min_thickness 0.25)
			(keepout
				(tracks not_allowed)
				(vias allowed)
				(pads allowed)
				(copperpour not_allowed)
				(footprints allowed)
			)
			(placement
				(enabled no)
				(sheetname "")
			)
			(fill
				(thermal_gap 0.5)
				(thermal_bridge_width 0.5)
				(island_removal_mode 0)
			)
			(polygon
				(pts
					(xy 178.308 -84.963) (xy 177.8 -84.963) (xy 177.8 -84.582) (xy 178.308 -84.582)
				)
			)
		)
		(zone
			(layer "F.Cu")
			(hatch none 0.5)
			(connect_pads
				(clearance 0)
			)
			(min_thickness 0.25)
			(keepout
				(tracks allowed)
				(vias not_allowed)
				(pads allowed)
				(copperpour not_allowed)
				(footprints allowed)
			)
			(placement
				(enabled no)
				(sheetname "")
			)
			(fill
				(thermal_gap 0.5)
				(thermal_bridge_width 0.5)
				(island_removal_mode 0)
			)
			(polygon
				(pts
					(xy 178.308 -84.582) (xy 177.8 -84.582) (xy 177.8 -84.963) (xy 178.308 -84.963)
				)
			)
		)
	)
	(footprint ""
		(layer "F.Cu")
		(at 12.66952 -3.53441 180)
		(property "Reference" "R12W31"
			(at -0.8382 -0.67818 180)
			(unlocked yes)
			(layer "F.SilkS")
			(effects
				(font
					(size 0.4064 0.254)
					(thickness 0.1524)
				)
				(justify left)
			)
		)
		(property "Value" ""
			(at 0 0 180)
			(layer "F.Fab")
			(effects
				(font
					(size 1.27 1.27)
				)
			)
		)
		(duplicate_pad_numbers_are_jumpers no)
		(fp_poly
			(pts
				(xy -0.2794 -0.1016) (xy 0.2794 -0.1016) (xy 0.2794 0.9906) (xy -0.2794 0.9906)
			)
			(stroke
				(width 0)
				(type default)
			)
			(fill no)
			(layer "F.CrtYd")
		)
		(fp_line
			(start 0.2794 0.9906)
			(end 0.2794 -0.1016)
			(stroke
				(width 0.1)
				(type default)
			)
			(layer "F.Fab")
		)
		(fp_line
			(start 0.2794 -0.1016)
			(end -0.2794 -0.1016)
			(stroke
				(width 0.1)
				(type default)
			)
			(layer "F.Fab")
		)
		(fp_line
			(start -0.2794 0.9906)
			(end 0.2794 0.9906)
			(stroke
				(width 0.1)
				(type default)
			)
			(layer "F.Fab")
		)
		(fp_line
			(start -0.2794 -0.1016)
			(end -0.2794 0.9906)
			(stroke
				(width 0.1)
				(type default)
			)
			(layer "F.Fab")
		)
		(pad "1" smd rect
			(at 0 0 180)
			(size 0.508 0.508)
			(layers "F.Cu" "F.Mask" "F.Paste")
			(net "PU_VR_PVDDQ_GHJ_FAULT1")
		)
		(pad "2" smd rect
			(at 0 0.889 180)
			(size 0.508 0.508)
			(layers "F.Cu" "F.Mask" "F.Paste")
			(net "PWRGD_PVDDQ_GHJ")
		)
		(zone
			(layer "F.Cu")
			(hatch none 0.5)
			(connect_pads
				(clearance 0)
			)
			(min_thickness 0.25)
			(keepout
				(tracks not_allowed)
				(vias allowed)
				(pads allowed)
				(copperpour not_allowed)
				(footprints allowed)
			)
			(placement
				(enabled no)
				(sheetname "")
			)
			(fill
				(thermal_gap 0.5)
				(thermal_bridge_width 0.5)
				(island_removal_mode 0)
			)
			(polygon
				(pts
					(xy 12.92352 -4.16941) (xy 12.41552 -4.16941) (xy 12.41552 -3.78841) (xy 12.92352 -3.78841)
				)
			)
		)
		(zone
			(layer "F.Cu")
			(hatch none 0.5)
			(connect_pads
				(clearance 0)
			)
			(min_thickness 0.25)
			(keepout
				(tracks allowed)
				(vias not_allowed)
				(pads allowed)
				(copperpour not_allowed)
				(footprints allowed)
			)
			(placement
				(enabled no)
				(sheetname "")
			)
			(fill
				(thermal_gap 0.5)
				(thermal_bridge_width 0.5)
				(island_removal_mode 0)
			)
			(polygon
				(pts
					(xy 12.92352 -3.78841) (xy 12.41552 -3.78841) (xy 12.41552 -4.16941) (xy 12.92352 -4.16941)
				)
			)
		)
	)
)
